(kicad_pcb
	(version 20260206)
	(generator "pcbnew")
	(generator_version "10.0")
	(general
		(thickness 1.6)
		(legacy_teardrops no)
	)
	(paper "A4")
	(title_block
		(title "04192023_DAF0TMB3IC0_F0TG_MB_C_brd_V02_OCP.brd")
		(comment 1 "Grand Teton / footprints 7642-7647 of 8354")
	)
	(layers
		(0 "F.Cu" signal "TOP")
		(4 "In1.Cu" signal "GND")
		(6 "In2.Cu" signal "IN1")
		(8 "In3.Cu" signal "GND1")
		(10 "In4.Cu" signal "IN2")
		(12 "In5.Cu" signal "GND2")
		(14 "In6.Cu" signal "IN3")
		(16 "In7.Cu" signal "GND3")
		(18 "In8.Cu" signal "VCC")
		(20 "In9.Cu" signal "VCC1")
		(22 "In10.Cu" signal "GND4")
		(24 "In11.Cu" signal "IN4")
		(26 "In12.Cu" signal "GND5")
		(28 "In13.Cu" signal "IN5")
		(30 "In14.Cu" signal "GND6")
		(32 "In15.Cu" signal "IN6")
		(34 "In16.Cu" signal "GND7")
		(2 "B.Cu" signal "BOTTOM")
		(9 "F.Adhes" user "F.Adhesive")
		(11 "B.Adhes" user "B.Adhesive")
		(13 "F.Paste" user "Package Geometry/Pastemask Top")
		(15 "B.Paste" user "Package Geometry/Pastemask Bottom")
		(5 "F.SilkS" user "Ref Des/Silkscreen Top")
		(7 "B.SilkS" user "Ref Des/Silkscreen Bottom")
		(1 "F.Mask" user "Board Geometry/Soldermask Top")
		(3 "B.Mask" user "Board Geometry/Soldermask Bottom")
		(17 "Dwgs.User" user "User.Drawings")
		(19 "Cmts.User" user "User.Comments")
		(21 "Eco1.User" user "User.Eco1")
		(23 "Eco2.User" user "User.Eco2")
		(25 "Edge.Cuts" user "Board Geometry/Outline")
		(27 "Margin" user)
		(31 "F.CrtYd" user "Package Geometry/Place Bound Top")
		(29 "B.CrtYd" user "Package Geometry/Place Bound Bottom")
		(35 "F.Fab" user "Ref Des/Assembly Top")
		(33 "B.Fab" user "Ref Des/Assembly Bottom")
	)
	(footprint ""
		(layer "B.Cu")
		(at 228.494082 -322.17868 180)
		(property "Reference" "C1093"
			(at 0 0 0)
			(layer "B.SilkS")
			(hide yes)
			(effects
				(font
					(size 1.27 1.27)
				)
				(justify mirror)
			)
		)
		(property "Value" ""
			(at 0 0 0)
			(layer "B.Fab")
			(effects
				(font
					(size 1.27 1.27)
				)
				(justify mirror)
			)
		)
		(duplicate_pad_numbers_are_jumpers no)
		(fp_line
			(start 0.7874 0.4064)
			(end 0.7874 -0.4064)
			(stroke
				(width 0.1524)
				(type default)
			)
			(layer "B.SilkS")
		)
		(fp_line
			(start 0.7874 -0.4064)
			(end -0.7874 -0.4064)
			(stroke
				(width 0.1524)
				(type default)
			)
			(layer "B.SilkS")
		)
		(fp_line
			(start -0.7874 0.4064)
			(end 0.7874 0.4064)
			(stroke
				(width 0.1524)
				(type default)
			)
			(layer "B.SilkS")
		)
		(fp_line
			(start -0.7874 -0.4064)
			(end -0.7874 0.4064)
			(stroke
				(width 0.1524)
				(type default)
			)
			(layer "B.SilkS")
		)
		(fp_line
			(start 0.67945 0.3048)
			(end 0.67945 -0.305054)
			(stroke
				(width 0.1)
				(type default)
			)
			(layer "B.Fab")
		)
		(fp_line
			(start 0.67945 -0.305054)
			(end 0.12065 -0.305054)
			(stroke
				(width 0.1)
				(type default)
			)
			(layer "B.Fab")
		)
		(fp_line
			(start 0.12065 0.3048)
			(end 0.67945 0.3048)
			(stroke
				(width 0.1)
				(type default)
			)
			(layer "B.Fab")
		)
		(fp_line
			(start 0.12065 0.2794)
			(end 0.12065 0.3048)
			(stroke
				(width 0.1)
				(type default)
			)
			(layer "B.Fab")
		)
		(fp_line
			(start 0.12065 -0.2794)
			(end -0.12065 -0.2794)
			(stroke
				(width 0.1)
				(type default)
			)
			(layer "B.Fab")
		)
		(fp_line
			(start 0.12065 -0.305054)
			(end 0.12065 -0.2794)
			(stroke
				(width 0.1)
				(type default)
			)
			(layer "B.Fab")
		)
		(fp_line
			(start -0.120396 0.3048)
			(end -0.120396 0.2794)
			(stroke
				(width 0.1)
				(type default)
			)
			(layer "B.Fab")
		)
		(fp_line
			(start -0.120396 0.2794)
			(end 0.12065 0.2794)
			(stroke
				(width 0.1)
				(type default)
			)
			(layer "B.Fab")
		)
		(fp_line
			(start -0.12065 -0.2794)
			(end -0.12065 -0.3048)
			(stroke
				(width 0.1)
				(type default)
			)
			(layer "B.Fab")
		)
		(fp_line
			(start -0.12065 -0.3048)
			(end -0.67945 -0.3048)
			(stroke
				(width 0.1)
				(type default)
			)
			(layer "B.Fab")
		)
		(fp_line
			(start -0.67945 0.3048)
			(end -0.120396 0.3048)
			(stroke
				(width 0.1)
				(type default)
			)
			(layer "B.Fab")
		)
		(fp_line
			(start -0.67945 -0.3048)
			(end -0.67945 0.3048)
			(stroke
				(width 0.1)
				(type default)
			)
			(layer "B.Fab")
		)
		(pad "1" smd circle
			(at 0.40005 0)
			(size 0 0)
			(layers "B.Cu" "B.Mask" "B.Paste")
			(net "P5V_AUX_ADC_TIC")
		)
		(pad "2" smd circle
			(at -0.40005 0)
			(size 0 0)
			(layers "B.Cu" "B.Mask" "B.Paste")
			(net "GND")
		)
	)
	(footprint ""
		(layer "B.Cu")
		(at 107.383834 -272.284952 180)
		(property "Reference" "C2354"
			(at 0 0 0)
			(layer "B.SilkS")
			(hide yes)
			(effects
				(font
					(size 1.27 1.27)
				)
				(justify mirror)
			)
		)
		(property "Value" ""
			(at 0 0 0)
			(layer "B.Fab")
			(effects
				(font
					(size 1.27 1.27)
				)
				(justify mirror)
			)
		)
		(duplicate_pad_numbers_are_jumpers no)
		(fp_line
			(start 0.7874 0.4064)
			(end 0.7874 -0.4064)
			(stroke
				(width 0.1524)
				(type default)
			)
			(layer "B.SilkS")
		)
		(fp_line
			(start 0.7874 -0.4064)
			(end -0.7874 -0.4064)
			(stroke
				(width 0.1524)
				(type default)
			)
			(layer "B.SilkS")
		)
		(fp_line
			(start -0.7874 0.4064)
			(end 0.7874 0.4064)
			(stroke
				(width 0.1524)
				(type default)
			)
			(layer "B.SilkS")
		)
		(fp_line
			(start -0.7874 -0.4064)
			(end -0.7874 0.4064)
			(stroke
				(width 0.1524)
				(type default)
			)
			(layer "B.SilkS")
		)
		(fp_line
			(start 0.67945 0.3048)
			(end 0.67945 -0.305054)
			(stroke
				(width 0.1)
				(type default)
			)
			(layer "B.Fab")
		)
		(fp_line
			(start 0.67945 -0.305054)
			(end 0.12065 -0.305054)
			(stroke
				(width 0.1)
				(type default)
			)
			(layer "B.Fab")
		)
		(fp_line
			(start 0.12065 0.3048)
			(end 0.67945 0.3048)
			(stroke
				(width 0.1)
				(type default)
			)
			(layer "B.Fab")
		)
		(fp_line
			(start 0.12065 0.2794)
			(end 0.12065 0.3048)
			(stroke
				(width 0.1)
				(type default)
			)
			(layer "B.Fab")
		)
		(fp_line
			(start 0.12065 -0.2794)
			(end -0.12065 -0.2794)
			(stroke
				(width 0.1)
				(type default)
			)
			(layer "B.Fab")
		)
		(fp_line
			(start 0.12065 -0.305054)
			(end 0.12065 -0.2794)
			(stroke
				(width 0.1)
				(type default)
			)
			(layer "B.Fab")
		)
		(fp_line
			(start -0.120396 0.3048)
			(end -0.120396 0.2794)
			(stroke
				(width 0.1)
				(type default)
			)
			(layer "B.Fab")
		)
		(fp_line
			(start -0.120396 0.2794)
			(end 0.12065 0.2794)
			(stroke
				(width 0.1)
				(type default)
			)
			(layer "B.Fab")
		)
		(fp_line
			(start -0.12065 -0.2794)
			(end -0.12065 -0.3048)
			(stroke
				(width 0.1)
				(type default)
			)
			(layer "B.Fab")
		)
		(fp_line
			(start -0.12065 -0.3048)
			(end -0.67945 -0.3048)
			(stroke
				(width 0.1)
				(type default)
			)
			(layer "B.Fab")
		)
		(fp_line
			(start -0.67945 0.3048)
			(end -0.120396 0.3048)
			(stroke
				(width 0.1)
				(type default)
			)
			(layer "B.Fab")
		)
		(fp_line
			(start -0.67945 -0.3048)
			(end -0.67945 0.3048)
			(stroke
				(width 0.1)
				(type default)
			)
			(layer "B.Fab")
		)
		(pad "1" smd circle
			(at 0.40005 0)
			(size 0 0)
			(layers "B.Cu" "B.Mask" "B.Paste")
			(net "PVDDCR_CPU1_P1")
		)
		(pad "2" smd circle
			(at -0.40005 0)
			(size 0 0)
			(layers "B.Cu" "B.Mask" "B.Paste")
			(net "GND")
		)
	)
	(footprint ""
		(layer "B.Cu")
		(at 114.73434 -61.76391 -90)
		(property "Reference" "R6227"
			(at 0 0 90)
			(layer "B.SilkS")
			(hide yes)
			(effects
				(font
					(size 1.27 1.27)
				)
				(justify mirror)
			)
		)
		(property "Value" ""
			(at 0 0 90)
			(layer "B.Fab")
			(effects
				(font
					(size 1.27 1.27)
				)
				(justify mirror)
			)
		)
		(duplicate_pad_numbers_are_jumpers no)
		(fp_line
			(start -0.7874 0.4064)
			(end 0.7874 0.4064)
			(stroke
				(width 0.1524)
				(type default)
			)
			(layer "B.SilkS")
		)
		(fp_line
			(start 0.7874 0.4064)
			(end 0.7874 -0.4064)
			(stroke
				(width 0.1524)
				(type default)
			)
			(layer "B.SilkS")
		)
		(fp_line
			(start -0.7874 -0.4064)
			(end -0.7874 0.4064)
			(stroke
				(width 0.1524)
				(type default)
			)
			(layer "B.SilkS")
		)
		(fp_line
			(start 0.7874 -0.4064)
			(end -0.7874 -0.4064)
			(stroke
				(width 0.1524)
				(type default)
			)
			(layer "B.SilkS")
		)
		(fp_line
			(start -0.67945 0.3048)
			(end -0.120396 0.3048)
			(stroke
				(width 0.1)
				(type default)
			)
			(layer "B.Fab")
		)
		(fp_line
			(start -0.120396 0.3048)
			(end -0.120396 0.2794)
			(stroke
				(width 0.1)
				(type default)
			)
			(layer "B.Fab")
		)
		(fp_line
			(start 0.12065 0.3048)
			(end 0.67945 0.3048)
			(stroke
				(width 0.1)
				(type default)
			)
			(layer "B.Fab")
		)
		(fp_line
			(start 0.67945 0.3048)
			(end 0.67945 -0.305054)
			(stroke
				(width 0.1)
				(type default)
			)
			(layer "B.Fab")
		)
		(fp_line
			(start -0.120396 0.2794)
			(end 0.12065 0.2794)
			(stroke
				(width 0.1)
				(type default)
			)
			(layer "B.Fab")
		)
		(fp_line
			(start 0.12065 0.2794)
			(end 0.12065 0.3048)
			(stroke
				(width 0.1)
				(type default)
			)
			(layer "B.Fab")
		)
		(fp_line
			(start -0.12065 -0.2794)
			(end -0.12065 -0.3048)
			(stroke
				(width 0.1)
				(type default)
			)
			(layer "B.Fab")
		)
		(fp_line
			(start 0.12065 -0.2794)
			(end -0.12065 -0.2794)
			(stroke
				(width 0.1)
				(type default)
			)
			(layer "B.Fab")
		)
		(fp_line
			(start -0.67945 -0.3048)
			(end -0.67945 0.3048)
			(stroke
				(width 0.1)
				(type default)
			)
			(layer "B.Fab")
		)
		(fp_line
			(start -0.12065 -0.3048)
			(end -0.67945 -0.3048)
			(stroke
				(width 0.1)
				(type default)
			)
			(layer "B.Fab")
		)
		(fp_line
			(start 0.12065 -0.305054)
			(end 0.12065 -0.2794)
			(stroke
				(width 0.1)
				(type default)
			)
			(layer "B.Fab")
		)
		(fp_line
			(start 0.67945 -0.305054)
			(end 0.12065 -0.305054)
			(stroke
				(width 0.1)
				(type default)
			)
			(layer "B.Fab")
		)
		(pad "1" smd circle
			(at 0.40005 0 90)
			(size 0 0)
			(layers "B.Cu" "B.Mask" "B.Paste")
			(net "P3V3_AUX")
		)
		(pad "2" smd circle
			(at -0.40005 0 90)
			(size 0 0)
			(layers "B.Cu" "B.Mask" "B.Paste")
			(net "SMB_USB_CPU0_HUB1_SDA_R2")
		)
	)
	(footprint ""
		(layer "B.Cu")
		(at 197.523608 -103.465376)
		(property "Reference" "R233"
			(at 0 0 0)
			(layer "B.SilkS")
			(hide yes)
			(effects
				(font
					(size 1.27 1.27)
				)
				(justify mirror)
			)
		)
		(property "Value" ""
			(at 0 0 0)
			(layer "B.Fab")
			(effects
				(font
					(size 1.27 1.27)
				)
				(justify mirror)
			)
		)
		(duplicate_pad_numbers_are_jumpers no)
		(fp_line
			(start -0.7874 -0.4064)
			(end -0.7874 0.4064)
			(stroke
				(width 0.1524)
				(type default)
			)
			(layer "B.SilkS")
		)
		(fp_line
			(start -0.7874 0.4064)
			(end 0.7874 0.4064)
			(stroke
				(width 0.1524)
				(type default)
			)
			(layer "B.SilkS")
		)
		(fp_line
			(start 0.7874 -0.4064)
			(end -0.7874 -0.4064)
			(stroke
				(width 0.1524)
				(type default)
			)
			(layer "B.SilkS")
		)
		(fp_line
			(start 0.7874 0.4064)
			(end 0.7874 -0.4064)
			(stroke
				(width 0.1524)
				(type default)
			)
			(layer "B.SilkS")
		)
		(fp_line
			(start -0.67945 -0.3048)
			(end -0.67945 0.3048)
			(stroke
				(width 0.1)
				(type default)
			)
			(layer "B.Fab")
		)
		(fp_line
			(start -0.67945 0.3048)
			(end -0.120396 0.3048)
			(stroke
				(width 0.1)
				(type default)
			)
			(layer "B.Fab")
		)
		(fp_line
			(start -0.12065 -0.3048)
			(end -0.67945 -0.3048)
			(stroke
				(width 0.1)
				(type default)
			)
			(layer "B.Fab")
		)
		(fp_line
			(start -0.12065 -0.2794)
			(end -0.12065 -0.3048)
			(stroke
				(width 0.1)
				(type default)
			)
			(layer "B.Fab")
		)
		(fp_line
			(start -0.120396 0.2794)
			(end 0.12065 0.2794)
			(stroke
				(width 0.1)
				(type default)
			)
			(layer "B.Fab")
		)
		(fp_line
			(start -0.120396 0.3048)
			(end -0.120396 0.2794)
			(stroke
				(width 0.1)
				(type default)
			)
			(layer "B.Fab")
		)
		(fp_line
			(start 0.12065 -0.305054)
			(end 0.12065 -0.2794)
			(stroke
				(width 0.1)
				(type default)
			)
			(layer "B.Fab")
		)
		(fp_line
			(start 0.12065 -0.2794)
			(end -0.12065 -0.2794)
			(stroke
				(width 0.1)
				(type default)
			)
			(layer "B.Fab")
		)
		(fp_line
			(start 0.12065 0.2794)
			(end 0.12065 0.3048)
			(stroke
				(width 0.1)
				(type default)
			)
			(layer "B.Fab")
		)
		(fp_line
			(start 0.12065 0.3048)
			(end 0.67945 0.3048)
			(stroke
				(width 0.1)
				(type default)
			)
			(layer "B.Fab")
		)
		(fp_line
			(start 0.67945 -0.305054)
			(end 0.12065 -0.305054)
			(stroke
				(width 0.1)
				(type default)
			)
			(layer "B.Fab")
		)
		(fp_line
			(start 0.67945 0.3048)
			(end 0.67945 -0.305054)
			(stroke
				(width 0.1)
				(type default)
			)
			(layer "B.Fab")
		)
		(pad "1" smd circle
			(at 0.40005 0 180)
			(size 0 0)
			(layers "B.Cu" "B.Mask" "B.Paste")
			(net "PWRGD_PVDDCR_CPU1_P0")
		)
		(pad "2" smd circle
			(at -0.40005 0 180)
			(size 0 0)
			(layers "B.Cu" "B.Mask" "B.Paste")
			(net "FM_PWRGD_PVDDCR_CPU1_P0")
		)
	)
	(footprint ""
		(layer "B.Cu")
		(at 354.406454 -264.35431)
		(property "Reference" "C2602"
			(at 0 0 0)
			(layer "B.SilkS")
			(hide yes)
			(effects
				(font
					(size 1.27 1.27)
				)
				(justify mirror)
			)
		)
		(property "Value" ""
			(at 0 0 0)
			(layer "B.Fab")
			(effects
				(font
					(size 1.27 1.27)
				)
				(justify mirror)
			)
		)
		(duplicate_pad_numbers_are_jumpers no)
		(fp_line
			(start -0.7874 -0.4064)
			(end -0.7874 0.4064)
			(stroke
				(width 0.1524)
				(type default)
			)
			(layer "B.SilkS")
		)
		(fp_line
			(start -0.7874 0.4064)
			(end 0.7874 0.4064)
			(stroke
				(width 0.1524)
				(type default)
			)
			(layer "B.SilkS")
		)
		(fp_line
			(start 0.7874 -0.4064)
			(end -0.7874 -0.4064)
			(stroke
				(width 0.1524)
				(type default)
			)
			(layer "B.SilkS")
		)
		(fp_line
			(start 0.7874 0.4064)
			(end 0.7874 -0.4064)
			(stroke
				(width 0.1524)
				(type default)
			)
			(layer "B.SilkS")
		)
		(fp_line
			(start -0.67945 -0.3048)
			(end -0.67945 0.3048)
			(stroke
				(width 0.1)
				(type default)
			)
			(layer "B.Fab")
		)
		(fp_line
			(start -0.67945 0.3048)
			(end -0.120396 0.3048)
			(stroke
				(width 0.1)
				(type default)
			)
			(layer "B.Fab")
		)
		(fp_line
			(start -0.12065 -0.3048)
			(end -0.67945 -0.3048)
			(stroke
				(width 0.1)
				(type default)
			)
			(layer "B.Fab")
		)
		(fp_line
			(start -0.12065 -0.2794)
			(end -0.12065 -0.3048)
			(stroke
				(width 0.1)
				(type default)
			)
			(layer "B.Fab")
		)
		(fp_line
			(start -0.120396 0.2794)
			(end 0.12065 0.2794)
			(stroke
				(width 0.1)
				(type default)
			)
			(layer "B.Fab")
		)
		(fp_line
			(start -0.120396 0.3048)
			(end -0.120396 0.2794)
			(stroke
				(width 0.1)
				(type default)
			)
			(layer "B.Fab")
		)
		(fp_line
			(start 0.12065 -0.305054)
			(end 0.12065 -0.2794)
			(stroke
				(width 0.1)
				(type default)
			)
			(layer "B.Fab")
		)
		(fp_line
			(start 0.12065 -0.2794)
			(end -0.12065 -0.2794)
			(stroke
				(width 0.1)
				(type default)
			)
			(layer "B.Fab")
		)
		(fp_line
			(start 0.12065 0.2794)
			(end 0.12065 0.3048)
			(stroke
				(width 0.1)
				(type default)
			)
			(layer "B.Fab")
		)
		(fp_line
			(start 0.12065 0.3048)
			(end 0.67945 0.3048)
			(stroke
				(width 0.1)
				(type default)
			)
			(layer "B.Fab")
		)
		(fp_line
			(start 0.67945 -0.305054)
			(end 0.12065 -0.305054)
			(stroke
				(width 0.1)
				(type default)
			)
			(layer "B.Fab")
		)
		(fp_line
			(start 0.67945 0.3048)
			(end 0.67945 -0.305054)
			(stroke
				(width 0.1)
				(type default)
			)
			(layer "B.Fab")
		)
		(pad "1" smd circle
			(at 0.40005 0 180)
			(size 0 0)
			(layers "B.Cu" "B.Mask" "B.Paste")
			(net "PVDD11_S3_P0")
		)
		(pad "2" smd circle
			(at -0.40005 0 180)
			(size 0 0)
			(layers "B.Cu" "B.Mask" "B.Paste")
			(net "GND")
		)
	)
	(footprint ""
		(layer "B.Cu")
		(at 363.931454 -249.36831)
		(property "Reference" "C246"
			(at 0 0 0)
			(layer "B.SilkS")
			(hide yes)
			(effects
				(font
					(size 1.27 1.27)
				)
				(justify mirror)
			)
		)
		(property "Value" ""
			(at 0 0 0)
			(layer "B.Fab")
			(effects
				(font
					(size 1.27 1.27)
				)
				(justify mirror)
			)
		)
		(duplicate_pad_numbers_are_jumpers no)
		(fp_line
			(start -0.7874 -0.4064)
			(end -0.7874 0.4064)
			(stroke
				(width 0.1524)
				(type default)
			)
			(layer "B.SilkS")
		)
		(fp_line
			(start -0.7874 0.4064)
			(end 0.7874 0.4064)
			(stroke
				(width 0.1524)
				(type default)
			)
			(layer "B.SilkS")
		)
		(fp_line
			(start 0.7874 -0.4064)
			(end -0.7874 -0.4064)
			(stroke
				(width 0.1524)
				(type default)
			)
			(layer "B.SilkS")
		)
		(fp_line
			(start 0.7874 0.4064)
			(end 0.7874 -0.4064)
			(stroke
				(width 0.1524)
				(type default)
			)
			(layer "B.SilkS")
		)
		(fp_line
			(start -0.67945 -0.3048)
			(end -0.67945 0.3048)
			(stroke
				(width 0.1)
				(type default)
			)
			(layer "B.Fab")
		)
		(fp_line
			(start -0.67945 0.3048)
			(end -0.120396 0.3048)
			(stroke
				(width 0.1)
				(type default)
			)
			(layer "B.Fab")
		)
		(fp_line
			(start -0.12065 -0.3048)
			(end -0.67945 -0.3048)
			(stroke
				(width 0.1)
				(type default)
			)
			(layer "B.Fab")
		)
		(fp_line
			(start -0.12065 -0.2794)
			(end -0.12065 -0.3048)
			(stroke
				(width 0.1)
				(type default)
			)
			(layer "B.Fab")
		)
		(fp_line
			(start -0.120396 0.2794)
			(end 0.12065 0.2794)
			(stroke
				(width 0.1)
				(type default)
			)
			(layer "B.Fab")
		)
		(fp_line
			(start -0.120396 0.3048)
			(end -0.120396 0.2794)
			(stroke
				(width 0.1)
				(type default)
			)
			(layer "B.Fab")
		)
		(fp_line
			(start 0.12065 -0.305054)
			(end 0.12065 -0.2794)
			(stroke
				(width 0.1)
				(type default)
			)
			(layer "B.Fab")
		)
		(fp_line
			(start 0.12065 -0.2794)
			(end -0.12065 -0.2794)
			(stroke
				(width 0.1)
				(type default)
			)
			(layer "B.Fab")
		)
		(fp_line
			(start 0.12065 0.2794)
			(end 0.12065 0.3048)
			(stroke
				(width 0.1)
				(type default)
			)
			(layer "B.Fab")
		)
		(fp_line
			(start 0.12065 0.3048)
			(end 0.67945 0.3048)
			(stroke
				(width 0.1)
				(type default)
			)
			(layer "B.Fab")
		)
		(fp_line
			(start 0.67945 -0.305054)
			(end 0.12065 -0.305054)
			(stroke
				(width 0.1)
				(type default)
			)
			(layer "B.Fab")
		)
		(fp_line
			(start 0.67945 0.3048)
			(end 0.67945 -0.305054)
			(stroke
				(width 0.1)
				(type default)
			)
			(layer "B.Fab")
		)
		(pad "1" smd circle
			(at 0.40005 0 180)
			(size 0 0)
			(layers "B.Cu" "B.Mask" "B.Paste")
			(net "PVDDCR_CPU0_P0")
		)
		(pad "2" smd circle
			(at -0.40005 0 180)
			(size 0 0)
			(layers "B.Cu" "B.Mask" "B.Paste")
			(net "GND")
		)
	)
)
